# TIMECARD (Time Appliance Project (Time Card)) — schematic netlist excerpt (pin names and nets, part order shuffled) for the footprints in the layout excerpt that follows; sources: Cadence DE-HDL packaged netlist, KiCad conversion of R4006-B0001-02_R01.brd

R227  RESISTOR  10KOHM 1%  pkg SMC_0402R_H016  page 31 : \1\ = UNNAMED_515_CAPACITOR_I128_1 ; \2\ = SG
R446  RESISTOR  10KOHM 1%  pkg SMC_0402R_H016  page 24 : \1\ = XP3R3V_FT4232 ; \2\ = FTDI_EE_CS

(kicad_pcb
	(version 20260206)
	(generator "pcbnew")
	(generator_version "10.0")
	(general
		(thickness 1.6)
		(legacy_teardrops no)
	)
	(paper "A4")
	(title_block
		(title "timecard-production-celestica-r4006 — R4006-B0001-02_R01.brd")
		(comment 1 "Time Appliance Project (Time Card) / footprints 1051-1052 of 1113")
	)
	(layers
		(0 "F.Cu" signal "TOP")
		(4 "In1.Cu" signal "L02_GND1")
		(6 "In2.Cu" signal "L03_SIG1")
		(8 "In3.Cu" signal "L04_GND2")
		(10 "In4.Cu" signal "L05_VCC1")
		(12 "In5.Cu" signal "L06_VCC2")
		(14 "In6.Cu" signal "L07_GND3")
		(16 "In7.Cu" signal "L08_SIG2")
		(18 "In8.Cu" signal "L09_GND4")
		(2 "B.Cu" signal "BOTTOM")
		(9 "F.Adhes" user "F.Adhesive")
		(11 "B.Adhes" user "B.Adhesive")
		(13 "F.Paste" user "Package Geometry/Pastemask Top")
		(15 "B.Paste" user "Package Geometry/Pastemask Bottom")
		(5 "F.SilkS" user "Ref Des/Silkscreen Top")
		(7 "B.SilkS" user "Ref Des/Silkscreen Bottom")
		(1 "F.Mask" user "Board Geometry/Soldermask Top")
		(3 "B.Mask" user "Board Geometry/Soldermask Bottom")
		(17 "Dwgs.User" user "User.Drawings")
		(19 "Cmts.User" user "User.Comments")
		(21 "Eco1.User" user "User.Eco1")
		(23 "Eco2.User" user "User.Eco2")
		(25 "Edge.Cuts" user "Board Geometry/Outline")
		(27 "Margin" user)
		(31 "F.CrtYd" user "Package Geometry/Place Bound Top")
		(29 "B.CrtYd" user "Package Geometry/Place Bound Bottom")
		(35 "F.Fab" user "Ref Des/Assembly Top")
		(33 "B.Fab" user "Ref Des/Assembly Bottom")
	)
	(footprint ""
		(layer "B.Cu")
		(at 53.975 -90.17)
		(property "Reference" "R446"
			(at 0.127 -4.15163 0)
			(unlocked yes)
			(layer "B.SilkS")
			(effects
				(font
					(size 0.7874 0.5842)
					(thickness 0.1524)
				)
				(justify mirror)
			)
		)
		(property "Value" "VAL*"
			(at -0.02032 2.13233 0)
			(unlocked yes)
			(layer "B.Fab")
			(hide yes)
			(effects
				(font
					(size 0.7874 0.5842)
					(thickness 0.1524)
				)
				(justify mirror)
			)
		)
		(property "Tolerance" "TOL*"
			(at -0.044704 3.05435 0)
			(unlocked yes)
			(layer "Cmts.User")
			(hide yes)
			(effects
				(font
					(size 0.7874 0.5842)
					(thickness 0.1524)
				)
				(justify mirror)
			)
		)
		(property "User Part Number" "PARTNUM*"
			(at -0.02032 4.024884 0)
			(unlocked yes)
			(layer "Cmts.User")
			(hide yes)
			(effects
				(font
					(size 0.7874 0.5842)
					(thickness 0.1524)
				)
				(justify mirror)
			)
		)
		(property "Device Type" "RESISTOR-G155-11002-01,10KOHM,A"
			(at -0.008382 1.210564 0)
			(unlocked yes)
			(layer "B.Fab")
			(hide yes)
			(effects
				(font
					(size 0.7874 0.5842)
					(thickness 0.1524)
				)
				(justify mirror)
			)
		)
		(duplicate_pad_numbers_are_jumpers no)
		(fp_line
			(start -1.143 -0.5588)
			(end 1.143 -0.5588)
			(stroke
				(width 0.1)
				(type default)
			)
			(layer "B.SilkS")
		)
		(fp_line
			(start -1.143 0.5588)
			(end -1.143 -0.5588)
			(stroke
				(width 0.1)
				(type default)
			)
			(layer "B.SilkS")
		)
		(fp_line
			(start 1.143 -0.5588)
			(end 1.143 0.5588)
			(stroke
				(width 0.1)
				(type default)
			)
			(layer "B.SilkS")
		)
		(fp_line
			(start 1.143 0.5588)
			(end -1.143 0.5588)
			(stroke
				(width 0.1)
				(type default)
			)
			(layer "B.SilkS")
		)
		(fp_poly
			(pts
				(xy 1.143 0.5588) (xy -1.143 0.5588) (xy -1.143 -0.5588) (xy 1.143 -0.5588)
			)
			(stroke
				(width 0)
				(type default)
			)
			(fill no)
			(layer "B.CrtYd")
		)
		(fp_line
			(start -0.508 -0.3048)
			(end 0.508 -0.3048)
			(stroke
				(width 0.1)
				(type default)
			)
			(layer "B.Fab")
		)
		(fp_line
			(start -0.508 0.3048)
			(end -0.508 -0.3048)
			(stroke
				(width 0.1)
				(type default)
			)
			(layer "B.Fab")
		)
		(fp_line
			(start 0.508 -0.3048)
			(end 0.508 0.3048)
			(stroke
				(width 0.1)
				(type default)
			)
			(layer "B.Fab")
		)
		(fp_line
			(start 0.508 0.3048)
			(end -0.508 0.3048)
			(stroke
				(width 0.1)
				(type default)
			)
			(layer "B.Fab")
		)
		(pad "1" smd rect
			(at 0.5334 0 180)
			(size 0.7112 0.6096)
			(layers "B.Cu" "B.Mask" "B.Paste")
			(net "XP3R3V_FT4232")
		)
		(pad "2" smd rect
			(at -0.5334 0 180)
			(size 0.7112 0.6096)
			(layers "B.Cu" "B.Mask" "B.Paste")
			(net "FTDI_EE_CS")
		)
		(zone
			(layer "B.Cu")
			(hatch none 0.5)
			(connect_pads
				(clearance 0)
			)
			(min_thickness 0.25)
			(keepout
				(tracks not_allowed)
				(vias allowed)
				(pads allowed)
				(copperpour not_allowed)
				(footprints allowed)
			)
			(placement
				(enabled no)
				(sheetname "")
			)
			(fill
				(thermal_gap 0.5)
				(thermal_bridge_width 0.5)
				(island_removal_mode 0)
			)
			(polygon
				(pts
					(xy 54.0512 -89.8652) (xy 54.0512 -90.4748) (xy 53.8988 -90.4748) (xy 53.8988 -89.8652)
				)
			)
		)
		(zone
			(layer "B.Cu")
			(hatch none 0.5)
			(connect_pads
				(clearance 0)
			)
			(min_thickness 0.25)
			(keepout
				(tracks allowed)
				(vias not_allowed)
				(pads allowed)
				(copperpour not_allowed)
				(footprints allowed)
			)
			(placement
				(enabled no)
				(sheetname "")
			)
			(fill
				(thermal_gap 0.5)
				(thermal_bridge_width 0.5)
				(island_removal_mode 0)
			)
			(polygon
				(pts
					(xy 54.0512 -89.8652) (xy 54.0512 -90.4748) (xy 53.8988 -90.4748) (xy 53.8988 -89.8652)
				)
			)
		)
	)
	(footprint ""
		(layer "B.Cu")
		(at 146.6088 -17.2466 90)
		(property "Reference" "R227"
			(at -0.3556 1.81483 270)
			(unlocked yes)
			(layer "B.SilkS")
			(effects
				(font
					(size 0.7874 0.5842)
					(thickness 0.1524)
				)
				(justify mirror)
			)
		)
		(property "Value" "VAL*"
			(at -0.02032 2.13233 90)
			(unlocked yes)
			(layer "B.Fab")
			(hide yes)
			(effects
				(font
					(size 0.7874 0.5842)
					(thickness 0.1524)
				)
				(justify mirror)
			)
		)
		(property "Tolerance" "TOL*"
			(at -0.044704 3.05435 90)
			(unlocked yes)
			(layer "Cmts.User")
			(hide yes)
			(effects
				(font
					(size 0.7874 0.5842)
					(thickness 0.1524)
				)
				(justify mirror)
			)
		)
		(property "User Part Number" "PARTNUM*"
			(at -0.02032 4.024884 90)
			(unlocked yes)
			(layer "Cmts.User")
			(hide yes)
			(effects
				(font
					(size 0.7874 0.5842)
					(thickness 0.1524)
				)
				(justify mirror)
			)
		)
		(property "Device Type" "RESISTOR-G155-11002-01,10KOHM,A"
			(at -0.008382 1.210564 90)
			(unlocked yes)
			(layer "B.Fab")
			(hide yes)
			(effects
				(font
					(size 0.7874 0.5842)
					(thickness 0.1524)
				)
				(justify mirror)
			)
		)
		(duplicate_pad_numbers_are_jumpers no)
		(fp_line
			(start 1.143 -0.5588)
			(end 1.143 0.5588)
			(stroke
				(width 0.1)
				(type default)
			)
			(layer "B.SilkS")
		)
		(fp_line
			(start -1.143 -0.5588)
			(end 1.143 -0.5588)
			(stroke
				(width 0.1)
				(type default)
			)
			(layer "B.SilkS")
		)
		(fp_line
			(start 1.143 0.5588)
			(end -1.143 0.5588)
			(stroke
				(width 0.1)
				(type default)
			)
			(layer "B.SilkS")
		)
		(fp_line
			(start -1.143 0.5588)
			(end -1.143 -0.5588)
			(stroke
				(width 0.1)
				(type default)
			)
			(layer "B.SilkS")
		)
		(fp_rect
			(start 1.143 0.5588)
			(end -1.143 -0.5588)
			(stroke
				(width 0)
				(type default)
			)
			(fill no)
			(layer "B.CrtYd")
		)
		(fp_line
			(start 0.508 -0.3048)
			(end 0.508 0.3048)
			(stroke
				(width 0.1)
				(type default)
			)
			(layer "B.Fab")
		)
		(fp_line
			(start -0.508 -0.3048)
			(end 0.508 -0.3048)
			(stroke
				(width 0.1)
				(type default)
			)
			(layer "B.Fab")
		)
		(fp_line
			(start 0.508 0.3048)
			(end -0.508 0.3048)
			(stroke
				(width 0.1)
				(type default)
			)
			(layer "B.Fab")
		)
		(fp_line
			(start -0.508 0.3048)
			(end -0.508 -0.3048)
			(stroke
				(width 0.1)
				(type default)
			)
			(layer "B.Fab")
		)
		(pad "1" smd rect
			(at 0.5334 0 270)
			(size 0.7112 0.6096)
			(layers "B.Cu" "B.Mask" "B.Paste")
			(net "UNNAMED_515_CAPACITOR_I128_1")
		)
		(pad "2" smd rect
			(at -0.5334 0 270)
			(size 0.7112 0.6096)
			(layers "B.Cu" "B.Mask" "B.Paste")
			(net "SG")
		)
		(zone
			(layer "B.Cu")
			(hatch none 0.5)
			(connect_pads
				(clearance 0)
			)
			(min_thickness 0.25)
			(keepout
				(tracks allowed)
				(vias not_allowed)
				(pads allowed)
				(copperpour not_allowed)
				(footprints allowed)
			)
			(placement
				(enabled no)
				(sheetname "")
			)
			(fill
				(thermal_gap 0.5)
				(thermal_bridge_width 0.5)
				(island_removal_mode 0)
			)
			(polygon
				(pts
					(xy 146.9136 -17.3228) (xy 146.304 -17.3228) (xy 146.304 -17.1704) (xy 146.9136 -17.1704)
				)
			)
		)
	)
)
